# T6G (Grand Teton) — schematic netlist excerpt (pin names and nets, part order shuffled) for the footprints in the layout excerpt that follows; sources: Cadence DE-HDL packaged netlist, KiCad conversion of 04192023_DAF0TMB3IC0_F0TG_MB_C_brd_V02_OCP.brd

J19  SCONN288_DDR506112002KQ  IO  pkg DDR288S_1-1VXC  page 89
  VIN_BULK0  = P12V_MEM_CPU0
  RFU0  = NC
  VIN_MGMT  = P3V3_AUX
  HSCL  = I3C_SPD_DDRD_CPU0_SCL
  HSDA  = I3C_SPD_DDRD_CPU0_SDA
  VSS0  = GND
  DQ0_A  = M_D_CPU0_SA_DQ<0>
  VSS1  = GND
  DQ1_A  = M_D_CPU0_SA_DQ<1>
  VSS2  = GND
  DQS0_A_T  = M_D_CPU0_SA_DQS_DP<0>
  DQS0_A_C  = M_D_CPU0_SA_DQS_DN<0>
  VSS3  = GND
  DQ4_A  = M_D_CPU0_SA_DQ<4>
  VSS4  = GND
  DQ5_A  = M_D_CPU0_SA_DQ<5>
  VSS5  = GND
  DQ8_A  = M_D_CPU0_SA_DQ<8>
  VSS6  = GND
  DQ9_A  = M_D_CPU0_SA_DQ<9>
  VSS7  = GND
  DQS1_A_T  = M_D_CPU0_SA_DQS_DP<1>
  DQS1_A_C  = M_D_CPU0_SA_DQS_DN<1>
  VSS8  = GND
  DQ12_A  = M_D_CPU0_SA_DQ<12>
  VSS9  = GND
  DQ13_A  = M_D_CPU0_SA_DQ<13>
  VSS10  = GND
  DQ16_A  = M_D_CPU0_SA_DQ<16>
  VSS11  = GND
  DQ17_A  = M_D_CPU0_SA_DQ<17>
  VSS12  = GND
  DQS2_A_T  = M_D_CPU0_SA_DQS_DP<2>
  DQS2_A_C  = M_D_CPU0_SA_DQS_DN<2>
  VSS13  = GND
  DQ20_A  = M_D_CPU0_SA_DQ<20>
  VSS14  = GND
  DQ21_A  = M_D_CPU0_SA_DQ<21>
  VSS15  = GND
  DQ24_A  = M_D_CPU0_SA_DQ<24>
  VSS16  = GND
  DQ25_A  = M_D_CPU0_SA_DQ<25>
  VSS17  = GND
  DQS3_A_T  = M_D_CPU0_SA_DQS_DP<3>
  DQS3_A_C  = M_D_CPU0_SA_DQS_DN<3>
  VSS18  = GND
  DQ28_A  = M_D_CPU0_SA_DQ<28>
  VSS19  = GND
  DQ29_A  = M_D_CPU0_SA_DQ<29>
  VSS20  = GND
  CB0_A  = M_D_CPU0_SA_CB<0>
  VSS21  = GND
  CB1_A  = M_D_CPU0_SA_CB<1>
  VSS22  = GND
  DQS4_A_T  = M_D_CPU0_SA_DQS_DP<4>
  DQS4_A_C  = M_D_CPU0_SA_DQS_DN<4>
  VSS23  = GND
  CB4_A  = M_D_CPU0_SA_CB<4>
  VSS24  = GND
  CB5_A  = M_D_CPU0_SA_CB<5>
  VSS25  = GND
  ALERT_N  = M_D_CPU0_ALERT_N
  VSS26  = GND
  CS0_A_N  = M_D_CPU0_SA_CS_N<0>
  VSS27  = GND
  CA0_A  = M_D_CPU0_SA_CA<0>
  VSS28  = GND
  CA2_A  = M_D_CPU0_SA_CA<2>
  VSS29  = GND
  CA4_A  = M_D_CPU0_SA_CA<4>
  VSS30  = GND
  CA6_A  = M_D_CPU0_SA_CA<6>
  VSS31  = GND
  PAR_A  = M_D_CPU0_SA_PAR
  VSS32  = GND
  CA0_B  = M_D_CPU0_SB_CA<0>
  VSS33  = GND
  CA2_B  = M_D_CPU0_SB_CA<2>
  VSS34  = GND
  CA4_B  = M_D_CPU0_SB_CA<4>
  VSS35  = GND
  CA6_B  = M_D_CPU0_SB_CA<6>
  VSS36  = GND
  CS0_B_N  = M_D_CPU0_SB_CS_N<0>
  VSS37  = GND
  \lbd||rsp_a_n\  = M_D_CPU0_SA_RSP<0>
  \lbs||rsp_b_n\  = M_D_CPU0_SB_RSP<0>
  VSS38  = GND
  CB4_B  = M_D_CPU0_SB_CB<4>
  VSS39  = GND
  CB5_B  = M_D_CPU0_SB_CB<5>
  VSS40  = GND
  \dqs9_b_t||tdqs9_b_t||dbi4_b_n\  = M_D_CPU0_SB_DQS_DP<9>
  \dqs9_b_c||tdqs9_b_c\  = M_D_CPU0_SB_DQS_DN<9>
  VSS41  = GND
  CB0_B  = M_D_CPU0_SB_CB<0>
  VSS42  = GND
  CB1_B  = M_D_CPU0_SB_CB<1>
  VSS43  = GND
  DQ0_B  = M_D_CPU0_SB_DQ<0>
  VSS44  = GND
  DQ1_B  = M_D_CPU0_SB_DQ<1>
  VSS45  = GND
  DQS0_B_T  = M_D_CPU0_SB_DQS_DP<0>
  DQS0_B_C  = M_D_CPU0_SB_DQS_DN<0>
  VSS46  = GND
  DQ4_B  = M_D_CPU0_SB_DQ<4>
  VSS47  = GND
  DQ5_B  = M_D_CPU0_SB_DQ<5>
  VSS48  = GND
  DQ8_B  = M_D_CPU0_SB_DQ<8>
  VSS49  = GND
  DQ9_B  = M_D_CPU0_SB_DQ<9>
  VSS50  = GND
  DQS1_B_T  = M_D_CPU0_SB_DQS_DP<1>
  DQS1_B_C  = M_D_CPU0_SB_DQS_DN<1>
  VSS51  = GND
  DQ12_B  = M_D_CPU0_SB_DQ<12>
  VSS52  = GND
  DQ13_B  = M_D_CPU0_SB_DQ<13>
  VSS53  = GND
  DQ16_B  = M_D_CPU0_SB_DQ<16>
  VSS54  = GND
  DQ17_B  = M_D_CPU0_SB_DQ<17>
  VSS55  = GND
  DQS2_B_T  = M_D_CPU0_SB_DQS_DP<2>
  DQS2_B_C  = M_D_CPU0_SB_DQS_DN<2>
  VSS56  = GND
  DQ20_B  = M_D_CPU0_SB_DQ<20>
  VSS57  = GND
  DQ21_B  = M_D_CPU0_SB_DQ<21>
  VSS58  = GND
  DQ24_B  = M_D_CPU0_SB_DQ<24>
  VSS59  = GND
  DQ25_B  = M_D_CPU0_SB_DQ<25>
  VSS60  = GND
  DQS3_B_T  = M_D_CPU0_SB_DQS_DP<3>
  DQS3_B_C  = M_D_CPU0_SB_DQS_DN<3>
  VSS61  = GND
  DQ28_B  = M_D_CPU0_SB_DQ<28>
  VSS62  = GND
  DQ29_B  = M_D_CPU0_SB_DQ<29>
  VSS63  = GND
  RFU1  = NC
  VIN_BULK1  = P12V_MEM_CPU0
  VIN_BULK2  = P12V_MEM_CPU0
  \pwr_good||fail_n\  = PWRGD_CHD_CPU0_DIMM
  HAS  = PD_CHD_CPU0_DIMM_SAA
  RFU2  = NC
  RFU3  = NC
  VSS64  = GND
  DQ2_A  = M_D_CPU0_SA_DQ<2>
  VSS65  = GND
  DQ3_A  = M_D_CPU0_SA_DQ<3>
  VSS66  = GND
  \dqs5_a_c||tdqs5_a_c||dqs5_a_t||tdqs5_a_t\  = M_D_CPU0_SA_DQS_DN<5>
  \dqs5_a_t||tdqs5_a_t\  = M_D_CPU0_SA_DQS_DP<5>
  VSS67  = GND
  DQ6_A  = M_D_CPU0_SA_DQ<6>
  VSS68  = GND
  DQ7_A  = M_D_CPU0_SA_DQ<7>
  VSS69  = GND
  DQ10_A  = M_D_CPU0_SA_DQ<10>
  VSS70  = GND
  DQ11_A  = M_D_CPU0_SA_DQ<11>
  VSS71  = GND
  \dqs6_a_c||tdqs6_a_c||dqs6_a_t||tdqs6_a_t\  = M_D_CPU0_SA_DQS_DN<6>
  \dqs6_a_t||tdqs6_a_t\  = M_D_CPU0_SA_DQS_DP<6>
  VSS72  = GND
  DQ14_A  = M_D_CPU0_SA_DQ<14>
  VSS73  = GND
  DQ15_A  = M_D_CPU0_SA_DQ<15>
  VSS74  = GND
  DQ18_A  = M_D_CPU0_SA_DQ<18>
  VSS75  = GND
  DQ19_A  = M_D_CPU0_SA_DQ<19>
  VSS76  = GND
  \dqs7_a_c||tdqs7_a_c\  = M_D_CPU0_SA_DQS_DN<7>
  \dqs7_a_t||tdqs7_a_t\  = M_D_CPU0_SA_DQS_DP<7>
  VSS77  = GND
  DQ22_A  = M_D_CPU0_SA_DQ<22>
  VSS78  = GND
  DQ23_A  = M_D_CPU0_SA_DQ<23>
  VSS79  = GND
  DQ26_A  = M_D_CPU0_SA_DQ<26>
  VSS80  = GND
  DQ27_A  = M_D_CPU0_SA_DQ<27>
  VSS81  = GND
  \dqs8_a_c||tdqs8_a_c\  = M_D_CPU0_SA_DQS_DN<8>
  \dqs8_a_t||tdqs8_a_t\  = M_D_CPU0_SA_DQS_DP<8>
  VSS82  = GND
  DQ30_A  = M_D_CPU0_SA_DQ<30>
  VSS83  = GND
  DQ31_A  = M_D_CPU0_SA_DQ<31>
  VSS84  = GND
  CB2_A  = M_D_CPU0_SA_CB<2>
  VSS85  = GND
  CB3_A  = M_D_CPU0_SA_CB<3>
  VSS86  = GND
  \dqs9_a_c||tdqs9_a_c\  = M_D_CPU0_SA_DQS_DN<9>
  \dqs9_a_t||tdqs9_a_t\  = M_D_CPU0_SA_DQS_DP<9>
  VSS87  = GND
  CB6_A  = M_D_CPU0_SA_CB<6>
  VSS88  = GND
  CB7_A  = M_D_CPU0_SA_CB<7>
  VSS89  = GND
  RESET_N  = M_D_CPU0_RESET_N
  VSS90  = GND
  CS1_A_N  = M_D_CPU0_SA_CS_N<1>
  VSS91  = GND
  CA1_A  = M_D_CPU0_SA_CA<1>
  VSS92  = GND
  CA3_A  = M_D_CPU0_SA_CA<3>
  VSS93  = GND
  CA5_A  = M_D_CPU0_SA_CA<5>
  VSS94  = GND
  CK_T  = M_D_CPU0_CLK_DP<0>
  CK_C  = M_D_CPU0_CLK_DN<0>
  VSS95  = GND
  RFU4  = NC
  CA1_B  = M_D_CPU0_SB_CA<1>
  VSS96  = GND
  CA3_B  = M_D_CPU0_SB_CA<3>
  VSS97  = GND
  CA5_B  = M_D_CPU0_SB_CA<5>
  VSS98  = GND
  PAR_B  = M_D_CPU0_SB_PAR
  VSS99  = GND
  CS1_B_N  = M_D_CPU0_SB_CS_N<1>
  VSS100  = GND
  RFU5  = NC
  RFU6  = NC
  VSS101  = GND
  CB6_B  = M_D_CPU0_SB_CB<6>
  VSS102  = GND
  CB7_B  = M_D_CPU0_SB_CB<7>
  VSS103  = GND
  DQS4_B_C  = M_D_CPU0_SB_DQS_DN<4>
  DQS4_B_T  = M_D_CPU0_SB_DQS_DP<4>
  VSS104  = GND
  CB2_B  = M_D_CPU0_SB_CB<2>
  VSS105  = GND
  CB3_B  = M_D_CPU0_SB_CB<3>
  VSS106  = GND
  DQ2_B  = M_D_CPU0_SB_DQ<2>
  VSS107  = GND
  DQ3_B  = M_D_CPU0_SB_DQ<3>
  VSS108  = GND
  \dqs5_b_c||tdqs5_b_c\  = M_D_CPU0_SB_DQS_DN<5>
  \dqs5_b_t||tdqs5_b_t\  = M_D_CPU0_SB_DQS_DP<5>
  VSS109  = GND
  DQ6_B  = M_D_CPU0_SB_DQ<6>
  VSS110  = GND
  DQ7_B  = M_D_CPU0_SB_DQ<7>
  VSS111  = GND
  DQ10_B  = M_D_CPU0_SB_DQ<10>
  VSS112  = GND
  DQ11_B  = M_D_CPU0_SB_DQ<11>
  VSS113  = GND
  \dqs6_b_c||tdqs6_b_c\  = M_D_CPU0_SB_DQS_DN<6>
  \dqs6_b_t||tdqs6_b_t\  = M_D_CPU0_SB_DQS_DP<6>
  VSS114  = GND
  DQ14_B  = M_D_CPU0_SB_DQ<14>
  VSS115  = GND
  DQ15_B  = M_D_CPU0_SB_DQ<15>
  VSS116  = GND
  DQ18_B  = M_D_CPU0_SB_DQ<18>
  VSS117  = GND
  DQ19_B  = M_D_CPU0_SB_DQ<19>
  VSS118  = GND
  \dqs7_b_c||tdqs7_b_c\  = M_D_CPU0_SB_DQS_DN<7>
  \dqs7_b_t||tdqs7_b_t\  = M_D_CPU0_SB_DQS_DP<7>
  VSS119  = GND
  DQ22_B  = M_D_CPU0_SB_DQ<22>
  VSS120  = GND
  DQ23_B  = M_D_CPU0_SB_DQ<23>
  VSS121  = GND
  DQ26_B  = M_D_CPU0_SB_DQ<26>
  VSS122  = GND
  DQ27_B  = M_D_CPU0_SB_DQ<27>
  VSS123  = GND
  \dqs8_b_c||tdqs8_b_c\  = M_D_CPU0_SB_DQS_DN<8>
  \dqs8_b_t||tdqs8_b_t\  = M_D_CPU0_SB_DQS_DP<8>
  VSS124  = GND
  DQ30_B  = M_D_CPU0_SB_DQ<30>
  VSS125  = GND
  DQ31_B  = M_D_CPU0_SB_DQ<31>
  VSS126  = GND
  G1  = GND
  G2  = GND
  G3  = GND

(kicad_pcb
	(version 20260206)
	(generator "pcbnew")
	(generator_version "10.0")
	(general
		(thickness 1.6)
		(legacy_teardrops no)
	)
	(paper "A4")
	(title_block
		(title "04192023_DAF0TMB3IC0_F0TG_MB_C_brd_V02_OCP.brd")
		(comment 1 "Grand Teton / footprint 2350 of 8354 (J19), pads 139-184 of 291")
	)
	(layers
		(0 "F.Cu" signal "TOP")
		(4 "In1.Cu" signal "GND")
		(6 "In2.Cu" signal "IN1")
		(8 "In3.Cu" signal "GND1")
		(10 "In4.Cu" signal "IN2")
		(12 "In5.Cu" signal "GND2")
		(14 "In6.Cu" signal "IN3")
		(16 "In7.Cu" signal "GND3")
		(18 "In8.Cu" signal "VCC")
		(20 "In9.Cu" signal "VCC1")
		(22 "In10.Cu" signal "GND4")
		(24 "In11.Cu" signal "IN4")
		(26 "In12.Cu" signal "GND5")
		(28 "In13.Cu" signal "IN5")
		(30 "In14.Cu" signal "GND6")
		(32 "In15.Cu" signal "IN6")
		(34 "In16.Cu" signal "GND7")
		(2 "B.Cu" signal "BOTTOM")
		(9 "F.Adhes" user "F.Adhesive")
		(11 "B.Adhes" user "B.Adhesive")
		(13 "F.Paste" user "Package Geometry/Pastemask Top")
		(15 "B.Paste" user "Package Geometry/Pastemask Bottom")
		(5 "F.SilkS" user "Ref Des/Silkscreen Top")
		(7 "B.SilkS" user "Ref Des/Silkscreen Bottom")
		(1 "F.Mask" user "Board Geometry/Soldermask Top")
		(3 "B.Mask" user "Board Geometry/Soldermask Bottom")
		(17 "Dwgs.User" user "User.Drawings")
		(19 "Cmts.User" user "User.Comments")
		(21 "Eco1.User" user "User.Eco1")
		(23 "Eco2.User" user "User.Eco2")
		(25 "Edge.Cuts" user "Board Geometry/Outline")
		(27 "Margin" user)
		(31 "F.CrtYd" user "Package Geometry/Place Bound Top")
		(29 "B.CrtYd" user "Package Geometry/Place Bound Bottom")
		(35 "F.Fab" user "Ref Des/Assembly Top")
		(33 "B.Fab" user "Ref Des/Assembly Bottom")
	)
	(footprint ""
		(layer "F.Cu")
		(at 282.685998 -255.560068 180)
		(property "Reference" "J19"
			(at -2.2098 -81.984088 0)
			(unlocked yes)
			(layer "F.SilkS")
			(effects
				(font
					(size 0.7874 0.5842)
					(thickness 0.1524)
				)
			)
		)
		(property "Value" ""
			(at 0 0 180)
			(layer "F.Fab")
			(effects
				(font
					(size 1.27 1.27)
				)
			)
		)
		(duplicate_pad_numbers_are_jumpers no)
		(pad "139" smd rect
			(at -2.050034 59.075066 90)
			(size 0.519938 1.4986)
			(layers "F.Cu" "F.Mask" "F.Paste")
			(net "GND")
		)
		(pad "140" smd rect
			(at -2.050034 59.92495 90)
			(size 0.519938 1.4986)
			(layers "F.Cu" "F.Mask" "F.Paste")
			(net "M_D_CPU0_SB_DQ<28>")
		)
		(pad "141" smd rect
			(at -2.050034 60.775088 90)
			(size 0.519938 1.4986)
			(layers "F.Cu" "F.Mask" "F.Paste")
			(net "GND")
		)
		(pad "142" smd rect
			(at -2.050034 61.624972 90)
			(size 0.519938 1.4986)
			(layers "F.Cu" "F.Mask" "F.Paste")
			(net "M_D_CPU0_SB_DQ<29>")
		)
		(pad "143" smd rect
			(at -2.050034 62.47511 90)
			(size 0.519938 1.4986)
			(layers "F.Cu" "F.Mask" "F.Paste")
			(net "GND")
		)
		(pad "144" smd rect
			(at -2.050034 63.324994 90)
			(size 0.519938 1.4986)
			(layers "F.Cu" "F.Mask" "F.Paste")
			(net "Net_2292")
		)
		(pad "145" smd rect
			(at 2.050034 -63.324994 90)
			(size 0.519938 1.4986)
			(layers "F.Cu" "F.Mask" "F.Paste")
			(net "P12V_MEM_CPU0")
		)
		(pad "146" smd rect
			(at 2.050034 -62.47511 90)
			(size 0.519938 1.4986)
			(layers "F.Cu" "F.Mask" "F.Paste")
			(net "P12V_MEM_CPU0")
		)
		(pad "147" smd rect
			(at 2.050034 -61.624972 90)
			(size 0.519938 1.4986)
			(layers "F.Cu" "F.Mask" "F.Paste")
			(net "PWRGD_CHD_CPU0_DIMM")
		)
		(pad "148" smd rect
			(at 2.050034 -60.775088 90)
			(size 0.519938 1.4986)
			(layers "F.Cu" "F.Mask" "F.Paste")
			(net "PD_CHD_CPU0_DIMM_SAA")
		)
		(pad "149" smd rect
			(at 2.050034 -59.92495 90)
			(size 0.519938 1.4986)
			(layers "F.Cu" "F.Mask" "F.Paste")
			(net "Net_2293")
		)
		(pad "150" smd rect
			(at 2.050034 -59.075066 90)
			(size 0.519938 1.4986)
			(layers "F.Cu" "F.Mask" "F.Paste")
			(net "Net_2294")
		)
		(pad "151" smd rect
			(at 2.050034 -58.224928 90)
			(size 0.519938 1.4986)
			(layers "F.Cu" "F.Mask" "F.Paste")
			(net "GND")
		)
		(pad "152" smd rect
			(at 2.050034 -57.375044 90)
			(size 0.519938 1.4986)
			(layers "F.Cu" "F.Mask" "F.Paste")
			(net "M_D_CPU0_SA_DQ<2>")
		)
		(pad "153" smd rect
			(at 2.050034 -56.524906 90)
			(size 0.519938 1.4986)
			(layers "F.Cu" "F.Mask" "F.Paste")
			(net "GND")
		)
		(pad "154" smd rect
			(at 2.050034 -55.675022 90)
			(size 0.519938 1.4986)
			(layers "F.Cu" "F.Mask" "F.Paste")
			(net "M_D_CPU0_SA_DQ<3>")
		)
		(pad "155" smd rect
			(at 2.050034 -54.824884 90)
			(size 0.519938 1.4986)
			(layers "F.Cu" "F.Mask" "F.Paste")
			(net "GND")
		)
		(pad "156" smd rect
			(at 2.050034 -53.975 90)
			(size 0.519938 1.4986)
			(layers "F.Cu" "F.Mask" "F.Paste")
			(net "M_D_CPU0_SA_DQS_DN<5>")
		)
		(pad "157" smd rect
			(at 2.050034 -53.125116 90)
			(size 0.519938 1.4986)
			(layers "F.Cu" "F.Mask" "F.Paste")
			(net "M_D_CPU0_SA_DQS_DP<5>")
		)
		(pad "158" smd rect
			(at 2.050034 -52.274978 90)
			(size 0.519938 1.4986)
			(layers "F.Cu" "F.Mask" "F.Paste")
			(net "GND")
		)
		(pad "159" smd rect
			(at 2.050034 -51.425094 90)
			(size 0.519938 1.4986)
			(layers "F.Cu" "F.Mask" "F.Paste")
			(net "M_D_CPU0_SA_DQ<6>")
		)
		(pad "160" smd rect
			(at 2.050034 -50.574956 90)
			(size 0.519938 1.4986)
			(layers "F.Cu" "F.Mask" "F.Paste")
			(net "GND")
		)
		(pad "161" smd rect
			(at 2.050034 -49.725072 90)
			(size 0.519938 1.4986)
			(layers "F.Cu" "F.Mask" "F.Paste")
			(net "M_D_CPU0_SA_DQ<7>")
		)
		(pad "162" smd rect
			(at 2.050034 -48.874934 90)
			(size 0.519938 1.4986)
			(layers "F.Cu" "F.Mask" "F.Paste")
			(net "GND")
		)
		(pad "163" smd rect
			(at 2.050034 -48.02505 90)
			(size 0.519938 1.4986)
			(layers "F.Cu" "F.Mask" "F.Paste")
			(net "M_D_CPU0_SA_DQ<10>")
		)
		(pad "164" smd rect
			(at 2.050034 -47.174912 90)
			(size 0.519938 1.4986)
			(layers "F.Cu" "F.Mask" "F.Paste")
			(net "GND")
		)
		(pad "165" smd rect
			(at 2.050034 -46.325028 90)
			(size 0.519938 1.4986)
			(layers "F.Cu" "F.Mask" "F.Paste")
			(net "M_D_CPU0_SA_DQ<11>")
		)
		(pad "166" smd rect
			(at 2.050034 -45.47489 90)
			(size 0.519938 1.4986)
			(layers "F.Cu" "F.Mask" "F.Paste")
			(net "GND")
		)
		(pad "167" smd rect
			(at 2.050034 -44.625006 90)
			(size 0.519938 1.4986)
			(layers "F.Cu" "F.Mask" "F.Paste")
			(net "M_D_CPU0_SA_DQS_DN<6>")
		)
		(pad "168" smd rect
			(at 2.050034 -43.775122 90)
			(size 0.519938 1.4986)
			(layers "F.Cu" "F.Mask" "F.Paste")
			(net "M_D_CPU0_SA_DQS_DP<6>")
		)
		(pad "169" smd rect
			(at 2.050034 -42.924984 90)
			(size 0.519938 1.4986)
			(layers "F.Cu" "F.Mask" "F.Paste")
			(net "GND")
		)
		(pad "170" smd rect
			(at 2.050034 -42.0751 90)
			(size 0.519938 1.4986)
			(layers "F.Cu" "F.Mask" "F.Paste")
			(net "M_D_CPU0_SA_DQ<14>")
		)
		(pad "171" smd rect
			(at 2.050034 -41.224962 90)
			(size 0.519938 1.4986)
			(layers "F.Cu" "F.Mask" "F.Paste")
			(net "GND")
		)
		(pad "172" smd rect
			(at 2.050034 -40.375078 90)
			(size 0.519938 1.4986)
			(layers "F.Cu" "F.Mask" "F.Paste")
			(net "M_D_CPU0_SA_DQ<15>")
		)
		(pad "173" smd rect
			(at 2.050034 -39.52494 90)
			(size 0.519938 1.4986)
			(layers "F.Cu" "F.Mask" "F.Paste")
			(net "GND")
		)
		(pad "174" smd rect
			(at 2.050034 -38.675056 90)
			(size 0.519938 1.4986)
			(layers "F.Cu" "F.Mask" "F.Paste")
			(net "M_D_CPU0_SA_DQ<18>")
		)
		(pad "175" smd rect
			(at 2.050034 -37.824918 90)
			(size 0.519938 1.4986)
			(layers "F.Cu" "F.Mask" "F.Paste")
			(net "GND")
		)
		(pad "176" smd rect
			(at 2.050034 -36.975034 90)
			(size 0.519938 1.4986)
			(layers "F.Cu" "F.Mask" "F.Paste")
			(net "M_D_CPU0_SA_DQ<19>")
		)
		(pad "177" smd rect
			(at 2.050034 -36.124896 90)
			(size 0.519938 1.4986)
			(layers "F.Cu" "F.Mask" "F.Paste")
			(net "GND")
		)
		(pad "178" smd rect
			(at 2.050034 -35.275012 90)
			(size 0.519938 1.4986)
			(layers "F.Cu" "F.Mask" "F.Paste")
			(net "M_D_CPU0_SA_DQS_DN<7>")
		)
		(pad "179" smd rect
			(at 2.050034 -34.425128 90)
			(size 0.519938 1.4986)
			(layers "F.Cu" "F.Mask" "F.Paste")
			(net "M_D_CPU0_SA_DQS_DP<7>")
		)
		(pad "180" smd rect
			(at 2.050034 -33.57499 90)
			(size 0.519938 1.4986)
			(layers "F.Cu" "F.Mask" "F.Paste")
			(net "GND")
		)
		(pad "181" smd rect
			(at 2.050034 -32.725106 90)
			(size 0.519938 1.4986)
			(layers "F.Cu" "F.Mask" "F.Paste")
			(net "M_D_CPU0_SA_DQ<22>")
		)
		(pad "182" smd rect
			(at 2.050034 -31.874968 90)
			(size 0.519938 1.4986)
			(layers "F.Cu" "F.Mask" "F.Paste")
			(net "GND")
		)
		(pad "183" smd rect
			(at 2.050034 -31.025084 90)
			(size 0.519938 1.4986)
			(layers "F.Cu" "F.Mask" "F.Paste")
			(net "M_D_CPU0_SA_DQ<23>")
		)
		(pad "184" smd rect
			(at 2.050034 -30.174946 90)
			(size 0.519938 1.4986)
			(layers "F.Cu" "F.Mask" "F.Paste")
			(net "GND")
		)
	)
)
